(kicad_pcb
	(version 20241229)
	(generator "pcbnew")
	(generator_version "9.0")
	(general
		(thickness 1.6)
		(legacy_teardrops no)
	)
	(paper "A4")
	(title_block
		(title "OCuLink to PCIe adapter")
		(date "2025-06-18")
		(rev "1.0.0")
		(company "Antmicro Ltd")
		(comment 1 "www.antmicro.com")
		(comment 9 "footprints 44-48 of 159")
	)
	(layers
		(0 "F.Cu" signal)
		(4 "In1.Cu" signal)
		(6 "In2.Cu" signal)
		(2 "B.Cu" signal)
		(9 "F.Adhes" user "F.Adhesive")
		(11 "B.Adhes" user "B.Adhesive")
		(13 "F.Paste" user)
		(15 "B.Paste" user)
		(5 "F.SilkS" user "F.Silkscreen")
		(7 "B.SilkS" user "B.Silkscreen")
		(1 "F.Mask" user)
		(3 "B.Mask" user)
		(17 "Dwgs.User" user "User.Drawings")
		(19 "Cmts.User" user "User.Comments")
		(21 "Eco1.User" user "User.Eco1")
		(23 "Eco2.User" user "User.Eco2")
		(25 "Edge.Cuts" user)
		(27 "Margin" user)
		(31 "F.CrtYd" user "F.Courtyard")
		(29 "B.CrtYd" user "B.Courtyard")
		(35 "F.Fab" user)
		(33 "B.Fab" user)
	)
	(footprint "antmicro-footprints:C_0805_2012Metric"
		(layer "F.Cu")
		(at 136.35 93.5 -90)
		(descr "Capacitor SMD 0805")
		(tags "capacitor SMD 0805")
		(property "Reference" "C17"
			(at -2.5 4.75 90)
			(layer "F.SilkS")
			(effects
				(font
					(size 0.7 0.7)
					(thickness 0.15)
				)
				(justify right top)
			)
		)
		(property "Value" "C_22u_25V_0805"
			(at -2.055717 1.963153 90)
			(layer "F.Fab")
			(effects
				(font
					(size 0.7 0.7)
					(thickness 0.15)
				)
				(justify right top)
			)
		)
		(property "Datasheet" "https://product.samsungsem.com/mlcc/CL21A226MAYNNN.do"
			(at 0 0 90)
			(layer "F.Fab")
			(hide yes)
			(effects
				(font
					(size 1.27 1.27)
					(thickness 0.15)
				)
			)
		)
		(property "Description" "SMT Multilayer Ceramic Capacitor, 22uF, +/-20%, 25V, X5R, 0805 [2012 Metric]"
			(at 0 0 90)
			(layer "F.Fab")
			(hide yes)
			(effects
				(font
					(size 1.27 1.27)
					(thickness 0.15)
				)
			)
		)
		(property "MPN" "CL21A226MAYNNNE"
			(at 0 0 270)
			(unlocked yes)
			(layer "F.Fab")
			(hide yes)
			(effects
				(font
					(size 1 1)
					(thickness 0.15)
				)
			)
		)
		(property "Manufacturer" "Samsung Electro-Mechanics"
			(at 0 0 270)
			(unlocked yes)
			(layer "F.Fab")
			(hide yes)
			(effects
				(font
					(size 1 1)
					(thickness 0.15)
				)
			)
		)
		(property "License" "Apache-2.0"
			(at 0 0 270)
			(unlocked yes)
			(layer "F.Fab")
			(hide yes)
			(effects
				(font
					(size 1 1)
					(thickness 0.15)
				)
			)
		)
		(property "Author" "Antmicro"
			(at 0 0 270)
			(unlocked yes)
			(layer "F.Fab")
			(hide yes)
			(effects
				(font
					(size 1 1)
					(thickness 0.15)
				)
			)
		)
		(property "Val" "22u"
			(at 0 0 270)
			(unlocked yes)
			(layer "F.Fab")
			(hide yes)
			(effects
				(font
					(size 1 1)
					(thickness 0.15)
				)
			)
		)
		(property "Voltage" "25V"
			(at 0 0 270)
			(unlocked yes)
			(layer "F.Fab")
			(hide yes)
			(effects
				(font
					(size 1 1)
					(thickness 0.15)
				)
			)
		)
		(property "Dielectric" "X5R"
			(at 0 0 270)
			(unlocked yes)
			(layer "F.Fab")
			(hide yes)
			(effects
				(font
					(size 1 1)
					(thickness 0.15)
				)
			)
		)
		(property "Public" "False"
			(at 0 0 270)
			(unlocked yes)
			(layer "F.Fab")
			(hide yes)
			(effects
				(font
					(size 1 1)
					(thickness 0.15)
				)
			)
		)
		(sheetname "/USB-PD/")
		(sheetfile "usb-pd.kicad_sch")
		(attr smd)
		(fp_line
			(start -0.3 0.7)
			(end 0.3 0.7)
			(stroke
				(width 0.15)
				(type solid)
			)
			(layer "F.SilkS")
		)
		(fp_line
			(start -0.3 -0.7)
			(end 0.3 -0.7)
			(stroke
				(width 0.15)
				(type solid)
			)
			(layer "F.SilkS")
		)
		(fp_rect
			(start 1.95 -0.9)
			(end -1.95 0.9)
			(stroke
				(width 0.05)
				(type default)
			)
			(fill no)
			(layer "F.CrtYd")
		)
		(fp_rect
			(start -0.95 -0.675)
			(end 0.95 0.675)
			(stroke
				(width 0.15)
				(type solid)
			)
			(fill no)
			(layer "F.Fab")
		)
		(fp_text user "License: Apache-2.0"
			(at -1.9 4.947 90)
			(layer "F.Fab")
			(effects
				(font
					(size 0.7 0.7)
					(thickness 0.15)
				)
				(justify right top)
			)
		)
		(fp_text user "Author: Antmicro"
			(at -1.9 5.947 90)
			(layer "F.Fab")
			(effects
				(font
					(size 0.7 0.7)
					(thickness 0.15)
				)
				(justify right top)
			)
		)
		(fp_text user "${REFERENCE}"
			(at 0 0 90)
			(layer "F.Fab")
			(effects
				(font
					(size 0.7 0.7)
					(thickness 0.15)
				)
				(justify right top)
			)
		)
		(pad "1" smd roundrect
			(at -1.1 0 270)
			(size 1.2 1.3)
			(layers "F.Cu" "F.Mask" "F.Paste")
			(roundrect_rratio 0.25)
			(net 66 "GND")
			(pintype "passive")
		)
		(pad "2" smd roundrect
			(at 1.1 0 270)
			(size 1.2 1.3)
			(layers "F.Cu" "F.Mask" "F.Paste")
			(roundrect_rratio 0.25)
			(net 187 "/USB-PD/12V_CONV")
			(pintype "passive")
		)
	)
	(footprint "antmicro-footprints:R_0402_1005Metric"
		(layer "F.Cu")
		(at 143.781981 50.8 -90)
		(descr "Resistor SMD 0402")
		(tags "resistor SMD 0402")
		(property "Reference" "R51"
			(at 0.95 0.381981 270)
			(layer "F.SilkS")
			(effects
				(font
					(size 0.7 0.7)
					(thickness 0.15)
				)
				(justify right top)
			)
		)
		(property "Value" "R_0R_0402"
			(at -1.011843 1.772046 90)
			(layer "F.Fab")
			(effects
				(font
					(size 0.7 0.7)
					(thickness 0.15)
				)
				(justify right top)
			)
		)
		(property "Datasheet" "https://industrial.panasonic.com/cdbs/www-data/pdf/RDA0000/AOA0000C301.pdf"
			(at 0 0 90)
			(layer "F.Fab")
			(hide yes)
			(effects
				(font
					(size 1.27 1.27)
					(thickness 0.15)
				)
			)
		)
		(property "Description" "SMD Chip Resistor, Jumper, 0 ohm, 100 mW, 0402 [1005 Metric], Thick Film, General Purpose"
			(at 0 0 90)
			(layer "F.Fab")
			(hide yes)
			(effects
				(font
					(size 1.27 1.27)
					(thickness 0.15)
				)
			)
		)
		(property "MPN" "ERJ2GE0R00X"
			(at 0 0 270)
			(unlocked yes)
			(layer "F.Fab")
			(hide yes)
			(effects
				(font
					(size 1 1)
					(thickness 0.15)
				)
			)
		)
		(property "Manufacturer" "Panasonic"
			(at 0 0 270)
			(unlocked yes)
			(layer "F.Fab")
			(hide yes)
			(effects
				(font
					(size 1 1)
					(thickness 0.15)
				)
			)
		)
		(property "License" "Apache-2.0"
			(at 0 0 270)
			(unlocked yes)
			(layer "F.Fab")
			(hide yes)
			(effects
				(font
					(size 1 1)
					(thickness 0.15)
				)
			)
		)
		(property "Author" "Antmicro"
			(at 0 0 270)
			(unlocked yes)
			(layer "F.Fab")
			(hide yes)
			(effects
				(font
					(size 1 1)
					(thickness 0.15)
				)
			)
		)
		(property "Val" "0R"
			(at 0 0 270)
			(unlocked yes)
			(layer "F.Fab")
			(hide yes)
			(effects
				(font
					(size 1 1)
					(thickness 0.15)
				)
			)
		)
		(property "Tolerance" ""
			(at 0 0 270)
			(unlocked yes)
			(layer "F.Fab")
			(hide yes)
			(effects
				(font
					(size 1 1)
					(thickness 0.15)
				)
			)
		)
		(property "Current" "1A"
			(at 0 0 270)
			(unlocked yes)
			(layer "F.Fab")
			(hide yes)
			(effects
				(font
					(size 1 1)
					(thickness 0.15)
				)
			)
		)
		(sheetname "/OCuLink/")
		(sheetfile "oculink.kicad_sch")
		(attr smd)
		(fp_rect
			(start -0.925 -0.47)
			(end 0.925 0.47)
			(stroke
				(width 0.05)
				(type default)
			)
			(fill no)
			(layer "F.CrtYd")
		)
		(fp_rect
			(start -0.5 -0.25)
			(end 0.5 0.25)
			(stroke
				(width 0.15)
				(type solid)
			)
			(fill no)
			(layer "F.Fab")
		)
		(fp_text user "${REFERENCE}"
			(at 0 0 90)
			(layer "F.Fab")
			(effects
				(font
					(size 0.7 0.7)
					(thickness 0.15)
				)
				(justify right top)
			)
		)
		(fp_text user "Author: Antmicro"
			(at -0.95 4.169 90)
			(layer "F.Fab")
			(effects
				(font
					(size 0.7 0.7)
					(thickness 0.15)
				)
				(justify right top)
			)
		)
		(fp_text user "License: Apache-2.0"
			(at -0.949999 5.169 90)
			(layer "F.Fab")
			(effects
				(font
					(size 0.7 0.7)
					(thickness 0.15)
				)
				(justify right top)
			)
		)
		(pad "1" smd roundrect
			(at -0.48 0 270)
			(size 0.59 0.64)
			(layers "F.Cu" "F.Mask" "F.Paste")
			(roundrect_rratio 0.25)
			(net 182 "/OCuLink/~{CPRSNTC}")
			(pintype "passive")
		)
		(pad "2" smd roundrect
			(at 0.48 0 270)
			(size 0.59 0.64)
			(layers "F.Cu" "F.Mask" "F.Paste")
			(roundrect_rratio 0.25)
			(net 99 "/OCuLink/~{CPRSNT}")
			(pintype "passive")
		)
	)
	(footprint "antmicro-footprints:R_0402_1005Metric"
		(layer "F.Cu")
		(at 141.660661 50.8 -90)
		(descr "Resistor SMD 0402")
		(tags "resistor SMD 0402")
		(property "Reference" "R2"
			(at 0.95 0.410661 270)
			(layer "F.SilkS")
			(effects
				(font
					(size 0.7 0.7)
					(thickness 0.15)
				)
				(justify right top)
			)
		)
		(property "Value" "R_0R_0402"
			(at -1.011843 1.772046 90)
			(layer "F.Fab")
			(effects
				(font
					(size 0.7 0.7)
					(thickness 0.15)
				)
				(justify right top)
			)
		)
		(property "Datasheet" "https://industrial.panasonic.com/cdbs/www-data/pdf/RDA0000/AOA0000C301.pdf"
			(at 0 0 90)
			(layer "F.Fab")
			(hide yes)
			(effects
				(font
					(size 1.27 1.27)
					(thickness 0.15)
				)
			)
		)
		(property "Description" "SMD Chip Resistor, Jumper, 0 ohm, 100 mW, 0402 [1005 Metric], Thick Film, General Purpose"
			(at 0 0 90)
			(layer "F.Fab")
			(hide yes)
			(effects
				(font
					(size 1.27 1.27)
					(thickness 0.15)
				)
			)
		)
		(property "MPN" "ERJ2GE0R00X"
			(at 0 0 270)
			(unlocked yes)
			(layer "F.Fab")
			(hide yes)
			(effects
				(font
					(size 1 1)
					(thickness 0.15)
				)
			)
		)
		(property "Manufacturer" "Panasonic"
			(at 0 0 270)
			(unlocked yes)
			(layer "F.Fab")
			(hide yes)
			(effects
				(font
					(size 1 1)
					(thickness 0.15)
				)
			)
		)
		(property "License" "Apache-2.0"
			(at 0 0 270)
			(unlocked yes)
			(layer "F.Fab")
			(hide yes)
			(effects
				(font
					(size 1 1)
					(thickness 0.15)
				)
			)
		)
		(property "Author" "Antmicro"
			(at 0 0 270)
			(unlocked yes)
			(layer "F.Fab")
			(hide yes)
			(effects
				(font
					(size 1 1)
					(thickness 0.15)
				)
			)
		)
		(property "Val" "0R"
			(at 0 0 270)
			(unlocked yes)
			(layer "F.Fab")
			(hide yes)
			(effects
				(font
					(size 1 1)
					(thickness 0.15)
				)
			)
		)
		(property "Tolerance" ""
			(at 0 0 270)
			(unlocked yes)
			(layer "F.Fab")
			(hide yes)
			(effects
				(font
					(size 1 1)
					(thickness 0.15)
				)
			)
		)
		(property "Current" "1A"
			(at 0 0 270)
			(unlocked yes)
			(layer "F.Fab")
			(hide yes)
			(effects
				(font
					(size 1 1)
					(thickness 0.15)
				)
			)
		)
		(sheetname "/OCuLink/")
		(sheetfile "oculink.kicad_sch")
		(attr smd dnp)
		(fp_rect
			(start -0.925 -0.47)
			(end 0.925 0.47)
			(stroke
				(width 0.05)
				(type default)
			)
			(fill no)
			(layer "F.CrtYd")
		)
		(fp_rect
			(start -0.5 -0.25)
			(end 0.5 0.25)
			(stroke
				(width 0.15)
				(type solid)
			)
			(fill no)
			(layer "F.Fab")
		)
		(fp_text user "Author: Antmicro"
			(at -0.95 4.169 90)
			(layer "F.Fab")
			(effects
				(font
					(size 0.7 0.7)
					(thickness 0.15)
				)
				(justify right top)
			)
		)
		(fp_text user "${REFERENCE}"
			(at 0 0 90)
			(layer "F.Fab")
			(effects
				(font
					(size 0.7 0.7)
					(thickness 0.15)
				)
				(justify right top)
			)
		)
		(fp_text user "License: Apache-2.0"
			(at -0.949999 5.169 90)
			(layer "F.Fab")
			(effects
				(font
					(size 0.7 0.7)
					(thickness 0.15)
				)
				(justify right top)
			)
		)
		(pad "1" smd roundrect
			(at -0.48 0 270)
			(size 0.59 0.64)
			(layers "F.Cu" "F.Mask" "F.Paste")
			(roundrect_rratio 0.25)
			(net 95 "/OCuLink/I2C0C_SDA")
			(pintype "passive")
		)
		(pad "2" smd roundrect
			(at 0.48 0 270)
			(size 0.59 0.64)
			(layers "F.Cu" "F.Mask" "F.Paste")
			(roundrect_rratio 0.25)
			(net 103 "/OCuLink/I2C0.SDA")
			(pintype "passive")
		)
	)
	(footprint "antmicro-footprints:R_0402_1005Metric"
		(layer "F.Cu")
		(at 148.152 92 180)
		(descr "Resistor SMD 0402")
		(tags "resistor SMD 0402")
		(property "Reference" "R31"
			(at -3.448 0.5 180)
			(layer "F.SilkS")
			(effects
				(font
					(size 0.7 0.7)
					(thickness 0.15)
				)
				(justify right top)
			)
		)
		(property "Value" "R_68k_0402"
			(at -1.011843 1.772046 0)
			(layer "F.Fab")
			(effects
				(font
					(size 0.7 0.7)
					(thickness 0.15)
				)
				(justify right top)
			)
		)
		(property "Datasheet" "https://www.bourns.com/docs/product-datasheets/cr.pdf"
			(at 0 0 0)
			(layer "F.Fab")
			(hide yes)
			(effects
				(font
					(size 1.27 1.27)
					(thickness 0.15)
				)
			)
		)
		(property "Description" "SMD Chip Resistor"
			(at 0 0 0)
			(layer "F.Fab")
			(hide yes)
			(effects
				(font
					(size 1.27 1.27)
					(thickness 0.15)
				)
			)
		)
		(property "MPN" "CR0402-FX-6802GLF"
			(at 0 0 180)
			(unlocked yes)
			(layer "F.Fab")
			(hide yes)
			(effects
				(font
					(size 1 1)
					(thickness 0.15)
				)
			)
		)
		(property "Manufacturer" "Bourns"
			(at 0 0 180)
			(unlocked yes)
			(layer "F.Fab")
			(hide yes)
			(effects
				(font
					(size 1 1)
					(thickness 0.15)
				)
			)
		)
		(property "License" "Apache-2.0"
			(at 0 0 180)
			(unlocked yes)
			(layer "F.Fab")
			(hide yes)
			(effects
				(font
					(size 1 1)
					(thickness 0.15)
				)
			)
		)
		(property "Author" "Antmicro"
			(at 0 0 180)
			(unlocked yes)
			(layer "F.Fab")
			(hide yes)
			(effects
				(font
					(size 1 1)
					(thickness 0.15)
				)
			)
		)
		(property "Val" "68k"
			(at 0 0 180)
			(unlocked yes)
			(layer "F.Fab")
			(hide yes)
			(effects
				(font
					(size 1 1)
					(thickness 0.15)
				)
			)
		)
		(property "Tolerance" "1%"
			(at 0 0 180)
			(unlocked yes)
			(layer "F.Fab")
			(hide yes)
			(effects
				(font
					(size 1 1)
					(thickness 0.15)
				)
			)
		)
		(sheetname "/USB-PD/")
		(sheetfile "usb-pd.kicad_sch")
		(attr smd exclude_from_bom dnp)
		(fp_rect
			(start -0.925 -0.47)
			(end 0.925 0.47)
			(stroke
				(width 0.05)
				(type default)
			)
			(fill no)
			(layer "F.CrtYd")
		)
		(fp_rect
			(start -0.5 -0.25)
			(end 0.5 0.25)
			(stroke
				(width 0.15)
				(type solid)
			)
			(fill no)
			(layer "F.Fab")
		)
		(fp_text user "License: Apache-2.0"
			(at -0.949999 5.169 0)
			(layer "F.Fab")
			(effects
				(font
					(size 0.7 0.7)
					(thickness 0.15)
				)
				(justify right top)
			)
		)
		(fp_text user "${REFERENCE}"
			(at 0 0 0)
			(layer "F.Fab")
			(effects
				(font
					(size 0.7 0.7)
					(thickness 0.15)
				)
				(justify right top)
			)
		)
		(fp_text user "Author: Antmicro"
			(at -0.95 4.169 0)
			(layer "F.Fab")
			(effects
				(font
					(size 0.7 0.7)
					(thickness 0.15)
				)
				(justify right top)
			)
		)
		(pad "1" smd roundrect
			(at -0.48 0 180)
			(size 0.59 0.64)
			(layers "F.Cu" "F.Mask" "F.Paste")
			(roundrect_rratio 0.25)
			(net 66 "GND")
			(pintype "passive")
		)
		(pad "2" smd roundrect
			(at 0.48 0 180)
			(size 0.59 0.64)
			(layers "F.Cu" "F.Mask" "F.Paste")
			(roundrect_rratio 0.25)
			(net 155 "/USB-PD/12V_ILIM")
			(pintype "passive")
		)
	)
	(footprint "antmicro-footprints:C_0402_1005Metric"
		(layer "F.Cu")
		(at 122.8 138.6 -90)
		(descr "Capacitor SMD 0402")
		(tags "capacitor SMD 0402")
		(property "Reference" "C5"
			(at 1 0.4 90)
			(layer "F.SilkS")
			(effects
				(font
					(size 0.7 0.7)
					(thickness 0.15)
				)
				(justify right top)
			)
		)
		(property "Value" "C_1u_25V_0402"
			(at -1.022927 2.155213 90)
			(layer "F.Fab")
			(effects
				(font
					(size 0.7 0.7)
					(thickness 0.15)
				)
				(justify right top)
			)
		)
		(property "Datasheet" "https://www.murata.com/products/productdetail?partno=GRM155R61E105KE11%23"
			(at 0 0 90)
			(layer "F.Fab")
			(hide yes)
			(effects
				(font
					(size 1.27 1.27)
					(thickness 0.15)
				)
			)
		)
		(property "Description" "SMD Multilayer Ceramic Capacitor, 1 µF, 25 V, 0402 [1005 Metric], ± 10%, X5R, GRM Series"
			(at 0 0 90)
			(layer "F.Fab")
			(hide yes)
			(effects
				(font
					(size 1.27 1.27)
					(thickness 0.15)
				)
			)
		)
		(property "MPN" "GRM155R61E105KE11J"
			(at 0 0 270)
			(unlocked yes)
			(layer "F.Fab")
			(hide yes)
			(effects
				(font
					(size 1 1)
					(thickness 0.15)
				)
			)
		)
		(property "Manufacturer" "Murata"
			(at 0 0 270)
			(unlocked yes)
			(layer "F.Fab")
			(hide yes)
			(effects
				(font
					(size 1 1)
					(thickness 0.15)
				)
			)
		)
		(property "License" "Apache-2.0"
			(at 0 0 270)
			(unlocked yes)
			(layer "F.Fab")
			(hide yes)
			(effects
				(font
					(size 1 1)
					(thickness 0.15)
				)
			)
		)
		(property "Author" "Antmicro"
			(at 0 0 270)
			(unlocked yes)
			(layer "F.Fab")
			(hide yes)
			(effects
				(font
					(size 1 1)
					(thickness 0.15)
				)
			)
		)
		(property "Val" "1u"
			(at 0 0 270)
			(unlocked yes)
			(layer "F.Fab")
			(hide yes)
			(effects
				(font
					(size 1 1)
					(thickness 0.15)
				)
			)
		)
		(property "Voltage" "25V"
			(at 0 0 270)
			(unlocked yes)
			(layer "F.Fab")
			(hide yes)
			(effects
				(font
					(size 1 1)
					(thickness 0.15)
				)
			)
		)
		(property "Dielectric" "X5R"
			(at 0 0 270)
			(unlocked yes)
			(layer "F.Fab")
			(hide yes)
			(effects
				(font
					(size 1 1)
					(thickness 0.15)
				)
			)
		)
		(sheetname "/Power/")
		(sheetfile "power.kicad_sch")
		(attr smd)
		(fp_rect
			(start -0.925 -0.47)
			(end 0.925 0.47)
			(stroke
				(width 0.05)
				(type default)
			)
			(fill no)
			(layer "F.CrtYd")
		)
		(fp_line
			(start -0.494 0.248)
			(end -0.494 -0.25)
			(stroke
				(width 0.15)
				(type solid)
			)
			(layer "F.Fab")
		)
		(fp_line
			(start 0.504 0.248)
			(end -0.494 0.248)
			(stroke
				(width 0.15)
				(type solid)
			)
			(layer "F.Fab")
		)
		(fp_line
			(start -0.494 -0.25)
			(end 0.504 -0.25)
			(stroke
				(width 0.15)
				(type solid)
			)
			(layer "F.Fab")
		)
		(fp_line
			(start 0.504 -0.25)
			(end 0.504 0.248)
			(stroke
				(width 0.15)
				(type solid)
			)
			(layer "F.Fab")
		)
		(fp_text user "${REFERENCE}"
			(at 0 0 90)
			(layer "F.Fab")
			(effects
				(font
					(size 0.7 0.7)
					(thickness 0.15)
				)
				(justify right top)
			)
		)
		(fp_text user "Author: Antmicro"
			(at -0.939 3.399 90)
			(layer "F.Fab")
			(effects
				(font
					(size 0.7 0.7)
					(thickness 0.15)
				)
				(justify right top)
			)
		)
		(fp_text user "License: Apache-2.0"
			(at -0.939 5.799 90)
			(layer "F.Fab")
			(effects
				(font
					(size 0.7 0.7)
					(thickness 0.15)
				)
				(justify right top)
			)
		)
		(pad "1" smd roundrect
			(at -0.48 0 270)
			(size 0.59 0.64)
			(layers "F.Cu" "F.Mask" "F.Paste")
			(roundrect_rratio 0.25)
			(net 66 "GND")
			(pintype "passive")
		)
		(pad "2" smd roundrect
			(at 0.48 0 270)
			(size 0.59 0.64)
			(layers "F.Cu" "F.Mask" "F.Paste")
			(roundrect_rratio 0.25)
			(net 186 "/Power/3V3_CONV")
			(pintype "passive")
		)
	)
)
